(kicad_pcb
	(version 20260206)
	(generator "pcbnew")
	(generator_version "10.0")
	(general
		(thickness 1.6)
		(legacy_teardrops no)
	)
	(paper "A4")
	(title_block
		(title "Wiwynn_Tioga_Pass_MB.brd")
		(comment 1 "Tioga Pass / footprint 752 of 4770 (EU4D2), pads 43-65 of 65")
	)
	(layers
		(0 "F.Cu" signal "TOP")
		(4 "In1.Cu" signal "L2GND")
		(6 "In2.Cu" signal "L3")
		(8 "In3.Cu" signal "L4GND")
		(10 "In4.Cu" signal "L5")
		(12 "In5.Cu" signal "L6GND")
		(14 "In6.Cu" signal "L7VCC")
		(16 "In7.Cu" signal "L8VCC")
		(18 "In8.Cu" signal "L9GND")
		(20 "In9.Cu" signal "L10")
		(22 "In10.Cu" signal "L11GND")
		(24 "In11.Cu" signal "L12")
		(26 "In12.Cu" signal "L13GND")
		(2 "B.Cu" signal "BOTTOM")
		(9 "F.Adhes" user "F.Adhesive")
		(11 "B.Adhes" user "B.Adhesive")
		(13 "F.Paste" user "Package Geometry/Pastemask Top")
		(15 "B.Paste" user "Package Geometry/Pastemask Bottom")
		(5 "F.SilkS" user "Ref Des/Silkscreen Top")
		(7 "B.SilkS" user "Ref Des/Silkscreen Bottom")
		(1 "F.Mask" user "Board Geometry/Soldermask Top")
		(3 "B.Mask" user "Board Geometry/Soldermask Bottom")
		(17 "Dwgs.User" user "User.Drawings")
		(19 "Cmts.User" user "User.Comments")
		(21 "Eco1.User" user "User.Eco1")
		(23 "Eco2.User" user "User.Eco2")
		(25 "Edge.Cuts" user "Board Geometry/Outline")
		(27 "Margin" user)
		(31 "F.CrtYd" user "Package Geometry/Place Bound Top")
		(29 "B.CrtYd" user "Package Geometry/Place Bound Bottom")
		(35 "F.Fab" user "Ref Des/Assembly Top")
		(33 "B.Fab" user "Ref Des/Assembly Bottom")
	)
	(footprint ""
		(layer "F.Cu")
		(at 169.422826 -80.961992 90)
		(property "Reference" "EU4D2"
			(at -8.471662 1.773174 0)
			(unlocked yes)
			(layer "F.SilkS")
			(effects
				(font
					(size 0.7874 0.5842)
					(thickness 0.1524)
				)
				(justify left)
			)
		)
		(property "Value" ""
			(at 0 0 90)
			(layer "F.Fab")
			(effects
				(font
					(size 1.27 1.27)
				)
			)
		)
		(duplicate_pad_numbers_are_jumpers no)
		(pad "43" smd custom
			(at 4.3688 -1.250188 90)
			(size 0.0762 0.0762)
			(layers "F.Cu" "F.Mask" "F.Paste")
			(net "CLK_100M_CPU1_BCLK0_R_DN")
			(options
				(clearance outline)
				(anchor circle)
			)
			(primitives
				(gr_poly
					(pts
						(xy 0.381 0.1524)
						(arc
							(start -0.2286 0.1524)
							(mid -0.381 0)
							(end -0.2286 -0.1524)
						)
						(xy 0.381 -0.1524)
					)
					(width 0)
					(fill yes)
				)
			)
		)
		(pad "44" smd custom
			(at 4.3688 -1.750314 90)
			(size 0.0762 0.0762)
			(layers "F.Cu" "F.Mask" "F.Paste")
			(net "FM_DB1200ZL_BCLKS_EN_N")
			(options
				(clearance outline)
				(anchor circle)
			)
			(primitives
				(gr_poly
					(pts
						(xy 0.381 0.1524)
						(arc
							(start -0.2286 0.1524)
							(mid -0.381 0)
							(end -0.2286 -0.1524)
						)
						(xy 0.381 -0.1524)
					)
					(width 0)
					(fill yes)
				)
			)
		)
		(pad "45" smd custom
			(at 4.3688 -2.25044 90)
			(size 0.0762 0.0762)
			(layers "F.Cu" "F.Mask" "F.Paste")
			(net "FM_DB1200ZL_BCLKS_EN_N")
			(options
				(clearance outline)
				(anchor circle)
			)
			(primitives
				(gr_poly
					(pts
						(xy 0.381 0.1524)
						(arc
							(start -0.2286 0.1524)
							(mid -0.381 0)
							(end -0.2286 -0.1524)
						)
						(xy 0.381 -0.1524)
					)
					(width 0)
					(fill yes)
				)
			)
		)
		(pad "46" smd custom
			(at 4.3688 -2.750566 90)
			(size 0.0762 0.0762)
			(layers "F.Cu" "F.Mask" "F.Paste")
			(net "CLK_100M_CPU1_BCLK1_R_DP")
			(options
				(clearance outline)
				(anchor circle)
			)
			(primitives
				(gr_poly
					(pts
						(xy 0.381 0.1524)
						(arc
							(start -0.2286 0.1524)
							(mid -0.381 0)
							(end -0.2286 -0.1524)
						)
						(xy 0.381 -0.1524)
					)
					(width 0)
					(fill yes)
				)
			)
		)
		(pad "47" smd custom
			(at 4.3688 -3.250692 90)
			(size 0.0762 0.0762)
			(layers "F.Cu" "F.Mask" "F.Paste")
			(net "CLK_100M_CPU1_BCLK1_R_DN")
			(options
				(clearance outline)
				(anchor circle)
			)
			(primitives
				(gr_poly
					(pts
						(xy 0.381 0.1524)
						(arc
							(start -0.2286 0.1524)
							(mid -0.381 0)
							(end -0.2286 -0.1524)
						)
						(xy 0.381 -0.1524)
					)
					(width 0)
					(fill yes)
				)
			)
		)
		(pad "48" smd custom
			(at 4.3688 -3.750818 90)
			(size 0.0762 0.0762)
			(layers "F.Cu" "F.Mask" "F.Paste")
			(net "GND")
			(options
				(clearance outline)
				(anchor circle)
			)
			(primitives
				(gr_poly
					(pts
						(xy 0.381 0.1524)
						(arc
							(start -0.2286 0.1524)
							(mid -0.381 0)
							(end -0.2286 -0.1524)
						)
						(xy 0.381 -0.1524)
					)
					(width 0)
					(fill yes)
				)
			)
		)
		(pad "49" smd custom
			(at 3.751072 -4.3688 90)
			(size 0.0762 0.0762)
			(layers "F.Cu" "F.Mask" "F.Paste")
			(net "P3V3_DB1200")
			(options
				(clearance outline)
				(anchor circle)
			)
			(primitives
				(gr_poly
					(pts
						(xy 0.1524 -0.381)
						(arc
							(start 0.1524 0.2286)
							(mid 0 0.381)
							(end -0.1524 0.2286)
						)
						(xy -0.1524 -0.381)
					)
					(width 0)
					(fill yes)
				)
			)
		)
		(pad "50" smd custom
			(at 3.250946 -4.3688 90)
			(size 0.0762 0.0762)
			(layers "F.Cu" "F.Mask" "F.Paste")
			(net "CLK_100M_CPU1_BCLK2_R_DP")
			(options
				(clearance outline)
				(anchor circle)
			)
			(primitives
				(gr_poly
					(pts
						(xy 0.1524 -0.381)
						(arc
							(start 0.1524 0.2286)
							(mid 0 0.381)
							(end -0.1524 0.2286)
						)
						(xy -0.1524 -0.381)
					)
					(width 0)
					(fill yes)
				)
			)
		)
		(pad "51" smd custom
			(at 2.75082 -4.3688 90)
			(size 0.0762 0.0762)
			(layers "F.Cu" "F.Mask" "F.Paste")
			(net "CLK_100M_CPU1_BCLK2_R_DN")
			(options
				(clearance outline)
				(anchor circle)
			)
			(primitives
				(gr_poly
					(pts
						(xy 0.1524 -0.381)
						(arc
							(start 0.1524 0.2286)
							(mid 0 0.381)
							(end -0.1524 0.2286)
						)
						(xy -0.1524 -0.381)
					)
					(width 0)
					(fill yes)
				)
			)
		)
		(pad "52" smd custom
			(at 2.250694 -4.3688 90)
			(size 0.0762 0.0762)
			(layers "F.Cu" "F.Mask" "F.Paste")
			(net "FM_DB1200ZL_BCLKS_EN_N")
			(options
				(clearance outline)
				(anchor circle)
			)
			(primitives
				(gr_poly
					(pts
						(xy 0.1524 -0.381)
						(arc
							(start 0.1524 0.2286)
							(mid 0 0.381)
							(end -0.1524 0.2286)
						)
						(xy -0.1524 -0.381)
					)
					(width 0)
					(fill yes)
				)
			)
		)
		(pad "53" smd custom
			(at 1.750568 -4.3688 90)
			(size 0.0762 0.0762)
			(layers "F.Cu" "F.Mask" "F.Paste")
			(net "FM_CPU1_MCP_CLK_EN_N")
			(options
				(clearance outline)
				(anchor circle)
			)
			(primitives
				(gr_poly
					(pts
						(xy 0.1524 -0.381)
						(arc
							(start 0.1524 0.2286)
							(mid 0 0.381)
							(end -0.1524 0.2286)
						)
						(xy -0.1524 -0.381)
					)
					(width 0)
					(fill yes)
				)
			)
		)
		(pad "54" smd custom
			(at 1.250442 -4.3688 90)
			(size 0.0762 0.0762)
			(layers "F.Cu" "F.Mask" "F.Paste")
			(net "CLK_100M_CPU1_PE_REFCLK_R_DP")
			(options
				(clearance outline)
				(anchor circle)
			)
			(primitives
				(gr_poly
					(pts
						(xy 0.1524 -0.381)
						(arc
							(start 0.1524 0.2286)
							(mid 0 0.381)
							(end -0.1524 0.2286)
						)
						(xy -0.1524 -0.381)
					)
					(width 0)
					(fill yes)
				)
			)
		)
		(pad "55" smd custom
			(at 0.750316 -4.3688 90)
			(size 0.0762 0.0762)
			(layers "F.Cu" "F.Mask" "F.Paste")
			(net "CLK_100M_CPU1_PE_REFCLK_R_DN")
			(options
				(clearance outline)
				(anchor circle)
			)
			(primitives
				(gr_poly
					(pts
						(xy 0.1524 -0.381)
						(arc
							(start 0.1524 0.2286)
							(mid 0 0.381)
							(end -0.1524 0.2286)
						)
						(xy -0.1524 -0.381)
					)
					(width 0)
					(fill yes)
				)
			)
		)
		(pad "56" smd custom
			(at 0.25019 -4.3688 90)
			(size 0.0762 0.0762)
			(layers "F.Cu" "F.Mask" "F.Paste")
			(net "P3V3_DB1200")
			(options
				(clearance outline)
				(anchor circle)
			)
			(primitives
				(gr_poly
					(pts
						(xy 0.1524 -0.381)
						(arc
							(start 0.1524 0.2286)
							(mid 0 0.381)
							(end -0.1524 0.2286)
						)
						(xy -0.1524 -0.381)
					)
					(width 0)
					(fill yes)
				)
			)
		)
		(pad "57" smd custom
			(at -0.249936 -4.3688 90)
			(size 0.0762 0.0762)
			(layers "F.Cu" "F.Mask" "F.Paste")
			(net "P3V3_DB1200")
			(options
				(clearance outline)
				(anchor circle)
			)
			(primitives
				(gr_poly
					(pts
						(xy 0.1524 -0.381)
						(arc
							(start 0.1524 0.2286)
							(mid 0 0.381)
							(end -0.1524 0.2286)
						)
						(xy -0.1524 -0.381)
					)
					(width 0)
					(fill yes)
				)
			)
		)
		(pad "58" smd custom
			(at -0.750062 -4.3688 90)
			(size 0.0762 0.0762)
			(layers "F.Cu" "F.Mask" "F.Paste")
			(net "GND")
			(options
				(clearance outline)
				(anchor circle)
			)
			(primitives
				(gr_poly
					(pts
						(xy 0.1524 -0.381)
						(arc
							(start 0.1524 0.2286)
							(mid 0 0.381)
							(end -0.1524 0.2286)
						)
						(xy -0.1524 -0.381)
					)
					(width 0)
					(fill yes)
				)
			)
		)
		(pad "59" smd custom
			(at -1.250188 -4.3688 90)
			(size 0.0762 0.0762)
			(layers "F.Cu" "F.Mask" "F.Paste")
			(net "CLK_100M_CPU1_RC_REFCLK0_R_DP")
			(options
				(clearance outline)
				(anchor circle)
			)
			(primitives
				(gr_poly
					(pts
						(xy 0.1524 -0.381)
						(arc
							(start 0.1524 0.2286)
							(mid 0 0.381)
							(end -0.1524 0.2286)
						)
						(xy -0.1524 -0.381)
					)
					(width 0)
					(fill yes)
				)
			)
		)
		(pad "60" smd custom
			(at -1.750314 -4.3688 90)
			(size 0.0762 0.0762)
			(layers "F.Cu" "F.Mask" "F.Paste")
			(net "CLK_100M_CPU1_RC_REFCLK0_R_DN")
			(options
				(clearance outline)
				(anchor circle)
			)
			(primitives
				(gr_poly
					(pts
						(xy 0.1524 -0.381)
						(arc
							(start 0.1524 0.2286)
							(mid 0 0.381)
							(end -0.1524 0.2286)
						)
						(xy -0.1524 -0.381)
					)
					(width 0)
					(fill yes)
				)
			)
		)
		(pad "61" smd custom
			(at -2.25044 -4.3688 90)
			(size 0.0762 0.0762)
			(layers "F.Cu" "F.Mask" "F.Paste")
			(net "FM_CPU1_MCP_CLK_EN_N")
			(options
				(clearance outline)
				(anchor circle)
			)
			(primitives
				(gr_poly
					(pts
						(xy 0.1524 -0.381)
						(arc
							(start 0.1524 0.2286)
							(mid 0 0.381)
							(end -0.1524 0.2286)
						)
						(xy -0.1524 -0.381)
					)
					(width 0)
					(fill yes)
				)
			)
		)
		(pad "62" smd custom
			(at -2.750566 -4.3688 90)
			(size 0.0762 0.0762)
			(layers "F.Cu" "F.Mask" "F.Paste")
			(net "FM_CPU1_MCP_CLK_EN_N")
			(options
				(clearance outline)
				(anchor circle)
			)
			(primitives
				(gr_poly
					(pts
						(xy 0.1524 -0.381)
						(arc
							(start 0.1524 0.2286)
							(mid 0 0.381)
							(end -0.1524 0.2286)
						)
						(xy -0.1524 -0.381)
					)
					(width 0)
					(fill yes)
				)
			)
		)
		(pad "63" smd custom
			(at -3.250692 -4.3688 90)
			(size 0.0762 0.0762)
			(layers "F.Cu" "F.Mask" "F.Paste")
			(net "CLK_100M_CPU1_RC_REFCLK1_R_DP")
			(options
				(clearance outline)
				(anchor circle)
			)
			(primitives
				(gr_poly
					(pts
						(xy 0.1524 -0.381)
						(arc
							(start 0.1524 0.2286)
							(mid 0 0.381)
							(end -0.1524 0.2286)
						)
						(xy -0.1524 -0.381)
					)
					(width 0)
					(fill yes)
				)
			)
		)
		(pad "64" smd custom
			(at -3.750818 -4.3688 90)
			(size 0.0762 0.0762)
			(layers "F.Cu" "F.Mask" "F.Paste")
			(net "CLK_100M_CPU1_RC_REFCLK1_R_DN")
			(options
				(clearance outline)
				(anchor circle)
			)
			(primitives
				(gr_poly
					(pts
						(xy 0.1524 -0.381)
						(arc
							(start 0.1524 0.2286)
							(mid 0 0.381)
							(end -0.1524 0.2286)
						)
						(xy -0.1524 -0.381)
					)
					(width 0)
					(fill yes)
				)
			)
		)
		(pad "65" smd rect
			(at 0 0 90)
			(size 6.2484 6.2484)
			(layers "F.Cu" "F.Mask" "F.Paste")
			(net "GND")
		)
	)
)
